FILE_TYPE = CONNECTIVITY;
{Allegro Design Entry HDL 16.6-p007 (v16-6-112F) 10/10/2012}
"PAGE_NUMBER" = 61;
0"NC";
1"M_L_DQS_DP<17:0>";
2"M_L_DQS_DN<17:0>";
3"M_L_MA<17:0>";
4"M_L_BA<1:0>";
5"M_L_BG<1:0>";
6"M_L_CKE<3:0>";
7"M_L_CS_N<7:0>";
8"M_L_ODT<3:0>";
9"M_L_DQ<63:0>";
10"M_L_CLK_DN<3:0>";
11"M_L_CLK_DP<3:0>";
12"M_L_ECC<7:0>";
13"M_L_DQ<55>";
14"M_L_ECC<1>";
15"M_L_DQ<41>";
16"M_L_DQ<52>";
17"M_L_ODT<2>";
18"M_L_DQ<34>";
19"M_L_DQS_DN<0>";
20"M_L_C<2>";
21"M_L_ECC<0>";
22"M_L_ECC<2>";
23"M_L_ECC<3>";
24"M_L_ECC<4>";
25"M_L_ECC<5>";
26"M_L_ECC<6>";
27"M_L_ECC<7>";
28"M_L_DQ<0>";
29"M_L_DQ<1>";
30"M_L_DQ<2>";
31"M_L_DQ<3>";
32"M_L_DQ<4>";
33"M_L_DQ<5>";
34"M_L_DQ<6>";
35"M_L_DQ<7>";
36"M_L_DQ<8>";
37"M_L_DQ<9>";
38"M_L_DQ<10>";
39"M_L_CLK_DP<0>";
40"M_L_CLK_DP<1>";
41"M_L_CLK_DP<2>";
42"M_L_CLK_DP<3>";
43"M_L_CLK_DN<0>";
44"M_L_CLK_DN<1>";
45"M_L_CLK_DN<2>";
46"M_L_CLK_DN<3>";
47"M_L_DQ<11>";
48"M_L_DQ<12>";
49"M_L_DQ<13>";
50"M_L_DQ<14>";
51"M_L_DQ<15>";
52"M_L_DQ<16>";
53"M_L_DQ<17>";
54"M_L_DQ<18>";
55"M_L_DQ<19>";
56"M_L_DQ<20>";
57"M_L_DQ<21>";
58"M_L_DQ<22>";
59"M_L_DQ<23>";
60"M_L_DQ<24>";
61"M_L_DQ<25>";
62"M_L_DQ<26>";
63"M_L_DQ<27>";
64"M_L_DQ<28>";
65"M_L_DQ<29>";
66"M_L_DQ<30>";
67"M_L_DQ<31>";
68"M_L_DQ<32>";
69"M_L_DQ<33>";
70"M_L_DQ<35>";
71"M_L_DQ<36>";
72"M_L_DQ<37>";
73"M_L_DQ<38>";
74"M_L_DQ<39>";
75"M_L_DQ<40>";
76"M_L_DQ<42>";
77"M_L_DQ<43>";
78"M_L_DQ<44>";
79"M_L_DQ<45>";
80"M_L_DQ<46>";
81"M_L_DQ<47>";
82"M_L_DQ<48>";
83"M_L_DQ<49>";
84"M_L_DQ<50>";
85"M_L_DQ<51>";
86"M_L_DQ<53>";
87"M_L_DQ<54>";
88"M_L_DQ<56>";
89"M_L_DQ<57>";
90"M_L_DQ<58>";
91"M_L_DQ<59>";
92"M_L_DQ<60>";
93"M_L_DQ<61>";
94"M_L_DQ<62>";
95"M_L_DQ<63>";
96"M_L_ODT<0>";
97"M_L_ODT<1>";
98"M_L_ODT<3>";
99"M_L_MA<0>";
100"M_L_MA<1>";
101"M_L_MA<2>";
102"M_L_CS_N<0>";
103"M_L_CS_N<1>";
104"M_L_CS_N<2>";
105"M_L_CS_N<3>";
106"M_L_CS_N<4>";
107"M_L_CS_N<5>";
108"M_L_CS_N<6>";
109"M_L_CS_N<7>";
110"M_L_CKE<0>";
111"M_L_CKE<1>";
112"M_L_CKE<2>";
113"M_L_CKE<3>";
114"M_L_BG<0>";
115"M_L_BG<1>";
116"M_L_BA<0>";
117"M_L_BA<1>";
118"M_L_MA<3>";
119"M_L_MA<4>";
120"M_L_MA<5>";
121"M_L_MA<6>";
122"M_L_MA<7>";
123"M_L_MA<8>";
124"M_L_MA<9>";
125"M_L_MA<10>";
126"M_L_MA<11>";
127"M_L_MA<12>";
128"M_L_MA<13>";
129"M_L_MA<14>";
130"M_L_MA<15>";
131"M_L_MA<16>";
132"M_L_MA<17>";
133"M_L_DQS_DP<0>";
134"M_L_DQS_DP<1>";
135"M_L_DQS_DP<2>";
136"M_L_DQS_DP<3>";
137"M_L_DQS_DP<4>";
138"M_L_DQS_DP<5>";
139"M_L_DQS_DN<1>";
140"M_L_DQS_DN<2>";
141"M_L_DQS_DN<3>";
142"M_L_DQS_DN<4>";
143"M_L_DQS_DN<5>";
144"M_L_DQS_DN<6>";
145"M_L_DQS_DN<7>";
146"M_L_DQS_DN<8>";
147"M_L_DQS_DN<9>";
148"M_L_DQS_DN<10>";
149"M_L_DQS_DN<11>";
150"M_L_DQS_DN<12>";
151"M_L_DQS_DN<13>";
152"M_L_DQS_DN<14>";
153"M_L_DQS_DN<15>";
154"M_L_DQS_DN<16>";
155"M_L_DQS_DN<17>";
156"M_L_PAR";
157"M_L_ALERT_N";
158"M_L_ACT_N";
159"M_L_DQS_DP<6>";
160"M_L_DQS_DP<7>";
161"M_L_DQS_DP<8>";
162"M_L_DQS_DP<9>";
163"M_L_DQS_DP<10>";
164"M_L_DQS_DP<11>";
165"M_L_DQS_DP<12>";
166"M_L_DQS_DP<13>";
167"M_L_DQS_DP<14>";
168"M_L_DQS_DP<15>";
169"M_L_DQS_DP<16>";
170"M_L_DQS_DP<17>";
%"TAP"
"6","(-5575,825)","0","mstr_standard","I10";
;
CDS_LIB"mstr_standard"
BODY_TYPE"PLUMBING"
HDL_TAP"TRUE";
"B \NAC \NWC"11;
"S \NAC"
BN"0"39;
%"TAP"
"6","(-2850,1575)","2","mstr_standard","I100";
;
CDS_LIB"mstr_standard"
BODY_TYPE"PLUMBING"
HDL_TAP"TRUE";
"B \NAC \NWC"8;
"S \NAC"
BN"3"98;
%"TAP"
"6","(-2850,1525)","2","mstr_standard","I101";
;
CDS_LIB"mstr_standard"
BODY_TYPE"PLUMBING"
HDL_TAP"TRUE";
"B \NAC \NWC"8;
"S \NAC"
BN"2"17;
%"TAP"
"6","(-2850,1475)","2","mstr_standard","I102";
;
CDS_LIB"mstr_standard"
BODY_TYPE"PLUMBING"
HDL_TAP"TRUE";
"B \NAC \NWC"8;
"S \NAC"
BN"1"97;
%"TAP"
"6","(-2850,1675)","2","mstr_standard","I103";
;
CDS_LIB"mstr_standard"
BODY_TYPE"PLUMBING"
HDL_TAP"TRUE";
"B \NAC \NWC"6;
"S \NAC"
BN"0"110;
%"TAP"
"6","(-2850,1725)","2","mstr_standard","I104";
;
CDS_LIB"mstr_standard"
BODY_TYPE"PLUMBING"
HDL_TAP"TRUE";
"B \NAC \NWC"6;
"S \NAC"
BN"1"111;
%"TAP"
"6","(-2850,1775)","2","mstr_standard","I105";
;
CDS_LIB"mstr_standard"
BODY_TYPE"PLUMBING"
HDL_TAP"TRUE";
"B \NAC \NWC"6;
"S \NAC"
BN"2"112;
%"TAP"
"6","(-2850,1825)","2","mstr_standard","I106";
;
CDS_LIB"mstr_standard"
BODY_TYPE"PLUMBING"
HDL_TAP"TRUE";
"B \NAC \NWC"6;
"S \NAC"
BN"3"113;
%"TAP"
"6","(-2850,1925)","2","mstr_standard","I107";
;
CDS_LIB"mstr_standard"
BODY_TYPE"PLUMBING"
HDL_TAP"TRUE";
"B \NAC \NWC"3;
"S \NAC"
BN"0"99;
%"TAP"
"6","(-2850,1975)","2","mstr_standard","I108";
;
CDS_LIB"mstr_standard"
BODY_TYPE"PLUMBING"
HDL_TAP"TRUE";
"B \NAC \NWC"3;
"S \NAC"
BN"1"100;
%"TAP"
"6","(-2850,2075)","2","mstr_standard","I109";
;
CDS_LIB"mstr_standard"
BODY_TYPE"PLUMBING"
HDL_TAP"TRUE";
"B \NAC \NWC"3;
"S \NAC"
BN"3"118;
%"TAP"
"6","(-5575,925)","0","mstr_standard","I11";
;
CDS_LIB"mstr_standard"
BODY_TYPE"PLUMBING"
HDL_TAP"TRUE";
"B \NAC \NWC"11;
"S \NAC"
BN"2"41;
%"TAP"
"6","(-2850,2025)","2","mstr_standard","I110";
;
CDS_LIB"mstr_standard"
BODY_TYPE"PLUMBING"
HDL_TAP"TRUE";
"B \NAC \NWC"3;
"S \NAC"
BN"2"101;
%"TAP"
"6","(-2850,2125)","2","mstr_standard","I111";
;
CDS_LIB"mstr_standard"
BODY_TYPE"PLUMBING"
HDL_TAP"TRUE";
"B \NAC \NWC"3;
"S \NAC"
BN"4"119;
%"TAP"
"6","(-2850,2175)","2","mstr_standard","I112";
;
CDS_LIB"mstr_standard"
BODY_TYPE"PLUMBING"
HDL_TAP"TRUE";
"B \NAC \NWC"3;
"S \NAC"
BN"5"120;
%"TAP"
"6","(-2850,2225)","2","mstr_standard","I113";
;
CDS_LIB"mstr_standard"
BODY_TYPE"PLUMBING"
HDL_TAP"TRUE";
"B \NAC \NWC"3;
"S \NAC"
BN"6"121;
%"TAP"
"6","(-2850,2325)","2","mstr_standard","I114";
;
CDS_LIB"mstr_standard"
BODY_TYPE"PLUMBING"
HDL_TAP"TRUE";
"B \NAC \NWC"3;
"S \NAC"
BN"8"123;
%"TAP"
"6","(-2850,2275)","2","mstr_standard","I115";
;
CDS_LIB"mstr_standard"
BODY_TYPE"PLUMBING"
HDL_TAP"TRUE";
"B \NAC \NWC"3;
"S \NAC"
BN"7"122;
%"TAP"
"6","(-2850,2475)","2","mstr_standard","I116";
;
CDS_LIB"mstr_standard"
BODY_TYPE"PLUMBING"
HDL_TAP"TRUE";
"B \NAC \NWC"3;
"S \NAC"
BN"11"126;
%"TAP"
"6","(-2850,2425)","2","mstr_standard","I117";
;
CDS_LIB"mstr_standard"
BODY_TYPE"PLUMBING"
HDL_TAP"TRUE";
"B \NAC \NWC"3;
"S \NAC"
BN"10"125;
%"TAP"
"6","(-2850,2375)","2","mstr_standard","I118";
;
CDS_LIB"mstr_standard"
BODY_TYPE"PLUMBING"
HDL_TAP"TRUE";
"B \NAC \NWC"3;
"S \NAC"
BN"9"124;
%"TAP"
"6","(-2850,2525)","2","mstr_standard","I119";
;
CDS_LIB"mstr_standard"
BODY_TYPE"PLUMBING"
HDL_TAP"TRUE";
"B \NAC \NWC"3;
"S \NAC"
BN"12"127;
%"TAP"
"6","(-5575,975)","0","mstr_standard","I12";
;
CDS_LIB"mstr_standard"
BODY_TYPE"PLUMBING"
HDL_TAP"TRUE";
"B \NAC \NWC"11;
"S \NAC"
BN"3"42;
%"TAP"
"6","(-2850,2575)","2","mstr_standard","I120";
;
CDS_LIB"mstr_standard"
BODY_TYPE"PLUMBING"
HDL_TAP"TRUE";
"B \NAC \NWC"3;
"S \NAC"
BN"13"128;
%"TAP"
"6","(-2850,2625)","2","mstr_standard","I121";
;
CDS_LIB"mstr_standard"
BODY_TYPE"PLUMBING"
HDL_TAP"TRUE";
"B \NAC \NWC"3;
"S \NAC"
BN"14"129;
%"TAP"
"6","(-2850,2675)","2","mstr_standard","I122";
;
CDS_LIB"mstr_standard"
BODY_TYPE"PLUMBING"
HDL_TAP"TRUE";
"B \NAC \NWC"3;
"S \NAC"
BN"15"130;
%"TAP"
"6","(-2850,2725)","2","mstr_standard","I123";
;
CDS_LIB"mstr_standard"
BODY_TYPE"PLUMBING"
HDL_TAP"TRUE";
"B \NAC \NWC"3;
"S \NAC"
BN"16"131;
%"TAP"
"6","(-2850,2775)","2","mstr_standard","I124";
;
CDS_LIB"mstr_standard"
BODY_TYPE"PLUMBING"
HDL_TAP"TRUE";
"B \NAC \NWC"3;
"S \NAC"
BN"17"132;
%"TAP"
"6","(-2850,2925)","2","mstr_standard","I125";
;
CDS_LIB"mstr_standard"
BODY_TYPE"PLUMBING"
HDL_TAP"TRUE";
"B \NAC \NWC"2;
"S \NAC"
BN"1"139;
%"TAP"
"6","(-2850,2975)","2","mstr_standard","I126";
;
CDS_LIB"mstr_standard"
BODY_TYPE"PLUMBING"
HDL_TAP"TRUE";
"B \NAC \NWC"2;
"S \NAC"
BN"2"140;
%"TAP"
"6","(-2850,2875)","2","mstr_standard","I127";
;
CDS_LIB"mstr_standard"
BODY_TYPE"PLUMBING"
HDL_TAP"TRUE";
"B \NAC \NWC"2;
"S \NAC"
BN"0"19;
%"TAP"
"6","(-2850,3075)","2","mstr_standard","I128";
;
CDS_LIB"mstr_standard"
BODY_TYPE"PLUMBING"
HDL_TAP"TRUE";
"B \NAC \NWC"2;
"S \NAC"
BN"4"142;
%"TAP"
"6","(-2850,3025)","2","mstr_standard","I129";
;
CDS_LIB"mstr_standard"
BODY_TYPE"PLUMBING"
HDL_TAP"TRUE";
"B \NAC \NWC"2;
"S \NAC"
BN"3"141;
%"TAP"
"6","(-5575,1075)","0","mstr_standard","I13";
;
CDS_LIB"mstr_standard"
BODY_TYPE"PLUMBING"
HDL_TAP"TRUE";
"B \NAC \NWC"12;
"S \NAC"
BN"0"21;
%"TAP"
"6","(-2850,3125)","2","mstr_standard","I130";
;
CDS_LIB"mstr_standard"
BODY_TYPE"PLUMBING"
HDL_TAP"TRUE";
"B \NAC \NWC"2;
"S \NAC"
BN"5"143;
%"TAP"
"6","(-2850,3175)","2","mstr_standard","I131";
;
CDS_LIB"mstr_standard"
BODY_TYPE"PLUMBING"
HDL_TAP"TRUE";
"B \NAC \NWC"2;
"S \NAC"
BN"6"144;
%"TAP"
"6","(-2850,3225)","2","mstr_standard","I132";
;
CDS_LIB"mstr_standard"
BODY_TYPE"PLUMBING"
HDL_TAP"TRUE";
"B \NAC \NWC"2;
"S \NAC"
BN"7"145;
%"TAP"
"6","(-2850,3275)","2","mstr_standard","I133";
;
CDS_LIB"mstr_standard"
BODY_TYPE"PLUMBING"
HDL_TAP"TRUE";
"B \NAC \NWC"2;
"S \NAC"
BN"8"146;
%"TAP"
"6","(-2850,3325)","2","mstr_standard","I134";
;
CDS_LIB"mstr_standard"
BODY_TYPE"PLUMBING"
HDL_TAP"TRUE";
"B \NAC \NWC"2;
"S \NAC"
BN"9"147;
%"TAP"
"6","(-2850,3375)","2","mstr_standard","I135";
;
CDS_LIB"mstr_standard"
BODY_TYPE"PLUMBING"
HDL_TAP"TRUE";
"B \NAC \NWC"2;
"S \NAC"
BN"10"148;
%"TAP"
"6","(-2850,3475)","2","mstr_standard","I136";
;
CDS_LIB"mstr_standard"
BODY_TYPE"PLUMBING"
HDL_TAP"TRUE";
"B \NAC \NWC"2;
"S \NAC"
BN"12"150;
%"TAP"
"6","(-2850,3425)","2","mstr_standard","I137";
;
CDS_LIB"mstr_standard"
BODY_TYPE"PLUMBING"
HDL_TAP"TRUE";
"B \NAC \NWC"2;
"S \NAC"
BN"11"149;
%"TAP"
"6","(-2850,3625)","2","mstr_standard","I138";
;
CDS_LIB"mstr_standard"
BODY_TYPE"PLUMBING"
HDL_TAP"TRUE";
"B \NAC \NWC"2;
"S \NAC"
BN"15"153;
%"TAP"
"6","(-2850,3575)","2","mstr_standard","I139";
;
CDS_LIB"mstr_standard"
BODY_TYPE"PLUMBING"
HDL_TAP"TRUE";
"B \NAC \NWC"2;
"S \NAC"
BN"14"152;
%"TAP"
"6","(-5575,1125)","0","mstr_standard","I14";
;
CDS_LIB"mstr_standard"
BODY_TYPE"PLUMBING"
HDL_TAP"TRUE";
"B \NAC \NWC"12;
"S \NAC"
BN"1"14;
%"TAP"
"6","(-2850,3525)","2","mstr_standard","I140";
;
CDS_LIB"mstr_standard"
BODY_TYPE"PLUMBING"
HDL_TAP"TRUE";
"B \NAC \NWC"2;
"S \NAC"
BN"13"151;
%"TAP"
"6","(-2850,3675)","2","mstr_standard","I141";
;
CDS_LIB"mstr_standard"
BODY_TYPE"PLUMBING"
HDL_TAP"TRUE";
"B \NAC \NWC"2;
"S \NAC"
BN"16"154;
%"TAP"
"6","(-2850,3725)","2","mstr_standard","I142";
;
CDS_LIB"mstr_standard"
BODY_TYPE"PLUMBING"
HDL_TAP"TRUE";
"B \NAC \NWC"2;
"S \NAC"
BN"17"155;
%"TAP"
"6","(-2850,3825)","2","mstr_standard","I143";
;
CDS_LIB"mstr_standard"
BODY_TYPE"PLUMBING"
HDL_TAP"TRUE";
"B \NAC \NWC"1;
"S \NAC"
BN"0"133;
%"TAP"
"6","(-2850,3875)","2","mstr_standard","I144";
;
CDS_LIB"mstr_standard"
BODY_TYPE"PLUMBING"
HDL_TAP"TRUE";
"B \NAC \NWC"1;
"S \NAC"
BN"1"134;
%"TAP"
"6","(-2850,3925)","2","mstr_standard","I145";
;
CDS_LIB"mstr_standard"
BODY_TYPE"PLUMBING"
HDL_TAP"TRUE";
"B \NAC \NWC"1;
"S \NAC"
BN"2"135;
%"TAP"
"6","(-2850,3975)","2","mstr_standard","I146";
;
CDS_LIB"mstr_standard"
BODY_TYPE"PLUMBING"
HDL_TAP"TRUE";
"B \NAC \NWC"1;
"S \NAC"
BN"3"136;
%"TAP"
"6","(-5575,1175)","0","mstr_standard","I15";
;
CDS_LIB"mstr_standard"
BODY_TYPE"PLUMBING"
HDL_TAP"TRUE";
"B \NAC \NWC"12;
"S \NAC"
BN"2"22;
%"TAP"
"6","(-2850,4025)","2","mstr_standard","I157";
;
CDS_LIB"mstr_standard"
BODY_TYPE"PLUMBING"
HDL_TAP"TRUE";
"B \NAC \NWC"1;
"S \NAC"
BN"4"137;
%"TAP"
"6","(-2850,4125)","2","mstr_standard","I158";
;
CDS_LIB"mstr_standard"
BODY_TYPE"PLUMBING"
HDL_TAP"TRUE";
"B \NAC \NWC"1;
"S \NAC"
BN"6"159;
%"TAP"
"6","(-2850,4075)","2","mstr_standard","I159";
;
CDS_LIB"mstr_standard"
BODY_TYPE"PLUMBING"
HDL_TAP"TRUE";
"B \NAC \NWC"1;
"S \NAC"
BN"5"138;
%"TAP"
"6","(-5575,1275)","0","mstr_standard","I16";
;
CDS_LIB"mstr_standard"
BODY_TYPE"PLUMBING"
HDL_TAP"TRUE";
"B \NAC \NWC"12;
"S \NAC"
BN"4"24;
%"TAP"
"6","(-2850,4175)","2","mstr_standard","I160";
;
CDS_LIB"mstr_standard"
BODY_TYPE"PLUMBING"
HDL_TAP"TRUE";
"B \NAC \NWC"1;
"S \NAC"
BN"7"160;
%"TAP"
"6","(-2850,4225)","2","mstr_standard","I161";
;
CDS_LIB"mstr_standard"
BODY_TYPE"PLUMBING"
HDL_TAP"TRUE";
"B \NAC \NWC"1;
"S \NAC"
BN"8"161;
%"TAP"
"6","(-2850,4275)","2","mstr_standard","I162";
;
CDS_LIB"mstr_standard"
BODY_TYPE"PLUMBING"
HDL_TAP"TRUE";
"B \NAC \NWC"1;
"S \NAC"
BN"9"162;
%"TAP"
"6","(-2850,4325)","2","mstr_standard","I163";
;
CDS_LIB"mstr_standard"
BODY_TYPE"PLUMBING"
HDL_TAP"TRUE";
"B \NAC \NWC"1;
"S \NAC"
BN"10"163;
%"TAP"
"6","(-2850,4375)","2","mstr_standard","I164";
;
CDS_LIB"mstr_standard"
BODY_TYPE"PLUMBING"
HDL_TAP"TRUE";
"B \NAC \NWC"1;
"S \NAC"
BN"11"164;
%"TAP"
"6","(-2850,4525)","2","mstr_standard","I165";
;
CDS_LIB"mstr_standard"
BODY_TYPE"PLUMBING"
HDL_TAP"TRUE";
"B \NAC \NWC"1;
"S \NAC"
BN"14"167;
%"TAP"
"6","(-2850,4475)","2","mstr_standard","I166";
;
CDS_LIB"mstr_standard"
BODY_TYPE"PLUMBING"
HDL_TAP"TRUE";
"B \NAC \NWC"1;
"S \NAC"
BN"13"166;
%"TAP"
"6","(-2850,4425)","2","mstr_standard","I167";
;
CDS_LIB"mstr_standard"
BODY_TYPE"PLUMBING"
HDL_TAP"TRUE";
"B \NAC \NWC"1;
"S \NAC"
BN"12"165;
%"TAP"
"6","(-2850,4575)","2","mstr_standard","I168";
;
CDS_LIB"mstr_standard"
BODY_TYPE"PLUMBING"
HDL_TAP"TRUE";
"B \NAC \NWC"1;
"S \NAC"
BN"15"168;
%"TAP"
"6","(-2850,4625)","2","mstr_standard","I169";
;
CDS_LIB"mstr_standard"
BODY_TYPE"PLUMBING"
HDL_TAP"TRUE";
"B \NAC \NWC"1;
"S \NAC"
BN"16"169;
%"TAP"
"6","(-5575,1225)","0","mstr_standard","I17";
;
CDS_LIB"mstr_standard"
BODY_TYPE"PLUMBING"
HDL_TAP"TRUE";
"B \NAC \NWC"12;
"S \NAC"
BN"3"23;
%"TAP"
"6","(-2850,4675)","2","mstr_standard","I170";
;
CDS_LIB"mstr_standard"
BODY_TYPE"PLUMBING"
HDL_TAP"TRUE";
"B \NAC \NWC"1;
"S \NAC"
BN"17"170;
%"SKX_EXT_B"
"7","(-4175,2575)","0","chpset_lib","I172";
;
CDS_SEC"7"
LOCATION"U2D1"
PART_NUMBER"TBD"
MATERIAL"IC"
PACK_TYPE"BGA1"
SEC_TYPE"BGA1"
CDS_LIB"chpset_lib"
SEC"7"
CDS_LOCATION"U2D1";
"DDR4_PAR"
$PN"DV53"156;
"DDR4_ODT<0>"
$PN"DR50"96;
"DDR4_ODT<1>"
$PN"DN48"97;
"DDR4_ODT<2>"
$PN"DT49"17;
"DDR4_ODT<3>"
$PN"DM47"98;
"DDR4_MA<0>"
$PN"DW52"99;
"DDR4_MA<1>"
$PN"DW58"100;
"DDR4_MA<2>"
$PN"DV57"101;
"DDR4_MA<3>"
$PN"DR58"118;
"DDR4_MA<4>"
$PN"DT59"119;
"DDR4_MA<5>"
$PN"DN58"120;
"DDR4_MA<6>"
$PN"DM59"121;
"DDR4_MA<7>"
$PN"DK61"122;
"DDR4_MA<8>"
$PN"DJ60"123;
"DDR4_MA<9>"
$PN"DV59"124;
"DDR4_MA<10>"
$PN"DT55"125;
"DDR4_MA<11>"
$PN"DR60"126;
"DDR4_MA<12>"
$PN"DN60"127;
"DDR4_MA<13>"
$PN"DT51"128;
"DDR4_MA<14>"
$PN"DM51"129;
"DDR4_MA<15>"
$PN"DR52"130;
"DDR4_MA<16>"
$PN"DN52"131;
"DDR4_MA<17>"
$PN"DR48"132;
"DDR4_ECC<0>"
$PN"DY69"21;
"DDR4_ECC<1>"
$PN"EA68"14;
"DDR4_ECC<2>"
$PN"DV65"22;
"DDR4_ECC<3>"
$PN"DY65"23;
"DDR4_ECC<4>"
$PN"DU68"24;
"DDR4_ECC<5>"
$PN"DV69"25;
"DDR4_ECC<6>"
$PN"DU66"26;
"DDR4_ECC<7>"
$PN"EA66"27;
"DDR4_DQS_DP<0>"
$PN"CM81"133;
"DDR4_DQS_DP<1>"
$PN"DB81"134;
"DDR4_DQS_DP<2>"
$PN"EB79"135;
"DDR4_DQS_DP<3>"
$PN"ED73"136;
"DDR4_DQS_DP<4>"
$PN"DT41"137;
"DDR4_DQS_DP<5>"
$PN"EC32"138;
"DDR4_DQS_DP<6>"
$PN"EC26"159;
"DDR4_DQS_DP<7>"
$PN"DJ26"160;
"DDR4_DQS_DP<8>"
$PN"DY67"161;
"DDR4_DQS_DP<9>"
$PN"CP79"162;
"DDR4_DQS_DP<10>"
$PN"DD79"163;
"DDR4_DQS_DP<11>"
$PN"DV79"164;
"DDR4_DQS_DP<12>"
$PN"DY73"165;
"DDR4_DQS_DP<13>"
$PN"DM41"166;
"DDR4_DQS_DP<14>"
$PN"DW32"167;
"DDR4_DQS_DP<15>"
$PN"DW26"168;
"DDR4_DQS_DP<16>"
$PN"DE26"169;
"DDR4_DQS_DP<17>"
$PN"DT67"170;
"DDR4_DQS_DN<0>"
$PN"CL82"19;
"DDR4_DQS_DN<1>"
$PN"DA82"139;
"DDR4_DQS_DN<2>"
$PN"ED79"140;
"DDR4_DQS_DN<3>"
$PN"EF73"141;
"DDR4_DQS_DN<4>"
$PN"DV41"142;
"DDR4_DQS_DN<5>"
$PN"EE32"143;
"DDR4_DQS_DN<6>"
$PN"EE26"144;
"DDR4_DQS_DN<7>"
$PN"DL26"145;
"DDR4_DQS_DN<8>"
$PN"EB67"146;
"DDR4_DQS_DN<9>"
$PN"CN80"147;
"DDR4_DQS_DN<10>"
$PN"DC80"148;
"DDR4_DQS_DN<11>"
$PN"DY79"149;
"DDR4_DQS_DN<12>"
$PN"EB73"150;
"DDR4_DQS_DN<13>"
$PN"DP41"151;
"DDR4_DQS_DN<14>"
$PN"EA32"152;
"DDR4_DQS_DN<15>"
$PN"EA26"153;
"DDR4_DQS_DN<16>"
$PN"DG26"154;
"DDR4_DQS_DN<17>"
$PN"DV67"155;
"DDR4_DQ<0>"
$PN"CM79"28;
"DDR4_DQ<1>"
$PN"CK81"29;
"DDR4_DQ<2>"
$PN"CT81"30;
"DDR4_DQ<3>"
$PN"CR82"31;
"DDR4_DQ<4>"
$PN"CK79"32;
"DDR4_DQ<5>"
$PN"CJ80"33;
"DDR4_DQ<6>"
$PN"CR80"34;
"DDR4_DQ<7>"
$PN"CN82"35;
"DDR4_DQ<8>"
$PN"DB79"36;
"DDR4_DQ<9>"
$PN"CY81"37;
"DDR4_DQ<10>"
$PN"DE80"38;
"DDR4_DQ<11>"
$PN"DF81"47;
"DDR4_DQ<12>"
$PN"CY79"48;
"DDR4_DQ<13>"
$PN"CW80"49;
"DDR4_DQ<14>"
$PN"DC82"50;
"DDR4_DQ<15>"
$PN"DE82"51;
"DDR4_DQ<16>"
$PN"DW80"52;
"DDR4_DQ<17>"
$PN"EC80"53;
"DDR4_DQ<18>"
$PN"DY77"54;
"DDR4_DQ<19>"
$PN"EB77"55;
"DDR4_DQ<20>"
$PN"DY81"56;
"DDR4_DQ<21>"
$PN"EB81"57;
"DDR4_DQ<22>"
$PN"DW78"58;
"DDR4_DQ<23>"
$PN"EC78"59;
"DDR4_DQ<24>"
$PN"ED75"60;
"DDR4_DQ<25>"
$PN"EE74"61;
"DDR4_DQ<26>"
$PN"EB71"62;
"DDR4_DQ<27>"
$PN"ED71"63;
"DDR4_DQ<28>"
$PN"EA74"64;
"DDR4_DQ<29>"
$PN"EB75"65;
"DDR4_DQ<30>"
$PN"EA72"66;
"DDR4_DQ<31>"
$PN"EE72"67;
"DDR4_DQ<32>"
$PN"DU42"68;
"DDR4_DQ<33>"
$PN"DW42"69;
"DDR4_DQ<34>"
$PN"DP39"18;
"DDR4_DQ<35>"
$PN"DT39"70;
"DDR4_DQ<36>"
$PN"DL42"71;
"DDR4_DQ<37>"
$PN"DN42"72;
"DDR4_DQ<38>"
$PN"DN40"73;
"DDR4_DQ<39>"
$PN"DU40"74;
"DDR4_DQ<40>"
$PN"EC34"75;
"DDR4_DQ<41>"
$PN"ED33"15;
"DDR4_DQ<42>"
$PN"EA30"76;
"DDR4_DQ<43>"
$PN"EC30"77;
"DDR4_DQ<44>"
$PN"DY33"78;
"DDR4_DQ<45>"
$PN"EA34"79;
"DDR4_DQ<46>"
$PN"DY31"80;
"DDR4_DQ<47>"
$PN"ED31"81;
"DDR4_DQ<48>"
$PN"EC28"82;
"DDR4_DQ<49>"
$PN"ED27"83;
"DDR4_DQ<50>"
$PN"EA24"84;
"DDR4_DQ<51>"
$PN"EC24"85;
"DDR4_DQ<52>"
$PN"DY27"16;
"DDR4_DQ<53>"
$PN"EA28"86;
"DDR4_DQ<54>"
$PN"DY25"87;
"DDR4_DQ<55>"
$PN"ED25"13;
"DDR4_DQ<56>"
$PN"DF27"88;
"DDR4_DQ<57>"
$PN"DK27"89;
"DDR4_DQ<58>"
$PN"DD25"90;
"DDR4_DQ<59>"
$PN"DJ24"91;
"DDR4_DQ<60>"
$PN"DG28"92;
"DDR4_DQ<61>"
$PN"DJ28"93;
"DDR4_DQ<62>"
$PN"DF25"94;
"DDR4_DQ<63>"
$PN"DK25"95;
"DDR4_CS_N<0>"
$PN"DV51"102;
"DDR4_CS_N<1>"
$PN"DN50"103;
"DDR4_CS_N<2>"
$PN"DR46"104;
"DDR4_CS_N<3>"
$PN"DK47"105;
"DDR4_CS_N<4>"
$PN"DW50"106;
"DDR4_CS_N<5>"
$PN"DM49"107;
"DDR4_CS_N<6>"
$PN"DT45"108;
"DDR4_CS_N<7>"
$PN"DN46"109;
"DDR4_CLK_DP<0>"
$PN"DN54"39;
"DDR4_CLK_DP<1>"
$PN"DT53"40;
"DDR4_CLK_DP<2>"
$PN"DN56"41;
"DDR4_CLK_DP<3>"
$PN"DR56"42;
"DDR4_CLK_DN<0>"
$PN"DM55"43;
"DDR4_CLK_DN<1>"
$PN"DR54"44;
"DDR4_CLK_DN<2>"
$PN"DM57"45;
"DDR4_CLK_DN<3>"
$PN"DT57"46;
"DDR4_CKE<0>"
$PN"DM63"110;
"DDR4_CKE<1>"
$PN"DN64"111;
"DDR4_CKE<2>"
$PN"DL64"112;
"DDR4_CKE<3>"
$PN"DR64"113;
"DDR4_CID<2>"
$PN"DT47"20;
"DDR4_BG<0>"
$PN"DJ62"114;
"DDR4_BG<1>"
$PN"DM61"115;
"DDR4_BA<0>"
$PN"DM53"116;
"DDR4_BA<1>"
$PN"DV55"117;
"DDR4_ALERT_N"
$PN"DT61"157;
"DDR4_ACT_N"
$PN"DR62"158;
%"TAP"
"6","(-5575,1325)","0","mstr_standard","I18";
;
CDS_LIB"mstr_standard"
BODY_TYPE"PLUMBING"
HDL_TAP"TRUE";
"B \NAC \NWC"12;
"S \NAC"
BN"5"25;
%"TAP"
"6","(-5575,1375)","0","mstr_standard","I19";
;
CDS_LIB"mstr_standard"
BODY_TYPE"PLUMBING"
HDL_TAP"TRUE";
"B \NAC \NWC"12;
"S \NAC"
BN"6"26;
%"TAP"
"6","(-5575,1425)","0","mstr_standard","I20";
;
CDS_LIB"mstr_standard"
BODY_TYPE"PLUMBING"
HDL_TAP"TRUE";
"B \NAC \NWC"12;
"S \NAC"
BN"7"27;
%"TAP"
"6","(-5575,1525)","0","mstr_standard","I21";
;
CDS_LIB"mstr_standard"
BODY_TYPE"PLUMBING"
HDL_TAP"TRUE";
"B \NAC \NWC"9;
"S \NAC"
BN"0"28;
%"TAP"
"6","(-5575,1575)","0","mstr_standard","I22";
;
CDS_LIB"mstr_standard"
BODY_TYPE"PLUMBING"
HDL_TAP"TRUE";
"B \NAC \NWC"9;
"S \NAC"
BN"1"29;
%"TAP"
"6","(-5575,1625)","0","mstr_standard","I23";
;
CDS_LIB"mstr_standard"
BODY_TYPE"PLUMBING"
HDL_TAP"TRUE";
"B \NAC \NWC"9;
"S \NAC"
BN"2"30;
%"TAP"
"6","(-5575,1675)","0","mstr_standard","I24";
;
CDS_LIB"mstr_standard"
BODY_TYPE"PLUMBING"
HDL_TAP"TRUE";
"B \NAC \NWC"9;
"S \NAC"
BN"3"31;
%"TAP"
"6","(-5575,1725)","0","mstr_standard","I25";
;
CDS_LIB"mstr_standard"
BODY_TYPE"PLUMBING"
HDL_TAP"TRUE";
"B \NAC \NWC"9;
"S \NAC"
BN"4"32;
%"TAP"
"6","(-5575,1775)","0","mstr_standard","I26";
;
CDS_LIB"mstr_standard"
BODY_TYPE"PLUMBING"
HDL_TAP"TRUE";
"B \NAC \NWC"9;
"S \NAC"
BN"5"33;
%"TAP"
"6","(-5575,1825)","0","mstr_standard","I27";
;
CDS_LIB"mstr_standard"
BODY_TYPE"PLUMBING"
HDL_TAP"TRUE";
"B \NAC \NWC"9;
"S \NAC"
BN"6"34;
%"TAP"
"6","(-5575,1925)","0","mstr_standard","I28";
;
CDS_LIB"mstr_standard"
BODY_TYPE"PLUMBING"
HDL_TAP"TRUE";
"B \NAC \NWC"9;
"S \NAC"
BN"8"36;
%"TAP"
"6","(-5575,1875)","0","mstr_standard","I29";
;
CDS_LIB"mstr_standard"
BODY_TYPE"PLUMBING"
HDL_TAP"TRUE";
"B \NAC \NWC"9;
"S \NAC"
BN"7"35;
%"TAP"
"6","(-5575,1975)","0","mstr_standard","I31";
;
CDS_LIB"mstr_standard"
BODY_TYPE"PLUMBING"
HDL_TAP"TRUE";
"B \NAC \NWC"9;
"S \NAC"
BN"9"37;
%"TAP"
"6","(-5575,2025)","0","mstr_standard","I32";
;
CDS_LIB"mstr_standard"
BODY_TYPE"PLUMBING"
HDL_TAP"TRUE";
"B \NAC \NWC"9;
"S \NAC"
BN"10"38;
%"TAP"
"6","(-5575,2075)","0","mstr_standard","I33";
;
CDS_LIB"mstr_standard"
BODY_TYPE"PLUMBING"
HDL_TAP"TRUE";
"B \NAC \NWC"9;
"S \NAC"
BN"11"47;
%"TAP"
"6","(-5575,2125)","0","mstr_standard","I34";
;
CDS_LIB"mstr_standard"
BODY_TYPE"PLUMBING"
HDL_TAP"TRUE";
"B \NAC \NWC"9;
"S \NAC"
BN"12"48;
%"TAP"
"6","(-5575,2175)","0","mstr_standard","I35";
;
CDS_LIB"mstr_standard"
BODY_TYPE"PLUMBING"
HDL_TAP"TRUE";
"B \NAC \NWC"9;
"S \NAC"
BN"13"49;
%"TAP"
"6","(-5575,2225)","0","mstr_standard","I36";
;
CDS_LIB"mstr_standard"
BODY_TYPE"PLUMBING"
HDL_TAP"TRUE";
"B \NAC \NWC"9;
"S \NAC"
BN"14"50;
%"TAP"
"6","(-5575,2275)","0","mstr_standard","I37";
;
CDS_LIB"mstr_standard"
BODY_TYPE"PLUMBING"
HDL_TAP"TRUE";
"B \NAC \NWC"9;
"S \NAC"
BN"15"51;
%"TAP"
"6","(-5575,2325)","0","mstr_standard","I38";
;
CDS_LIB"mstr_standard"
BODY_TYPE"PLUMBING"
HDL_TAP"TRUE";
"B \NAC \NWC"9;
"S \NAC"
BN"16"52;
%"TAP"
"6","(-5575,2375)","0","mstr_standard","I39";
;
CDS_LIB"mstr_standard"
BODY_TYPE"PLUMBING"
HDL_TAP"TRUE";
"B \NAC \NWC"9;
"S \NAC"
BN"17"53;
%"TAP"
"6","(-5575,2425)","0","mstr_standard","I40";
;
CDS_LIB"mstr_standard"
BODY_TYPE"PLUMBING"
HDL_TAP"TRUE";
"B \NAC \NWC"9;
"S \NAC"
BN"18"54;
%"TAP"
"6","(-5575,2475)","0","mstr_standard","I41";
;
CDS_LIB"mstr_standard"
BODY_TYPE"PLUMBING"
HDL_TAP"TRUE";
"B \NAC \NWC"9;
"S \NAC"
BN"19"55;
%"TAP"
"6","(-5575,2525)","0","mstr_standard","I42";
;
CDS_LIB"mstr_standard"
BODY_TYPE"PLUMBING"
HDL_TAP"TRUE";
"B \NAC \NWC"9;
"S \NAC"
BN"20"56;
%"TAP"
"6","(-5575,2575)","0","mstr_standard","I43";
;
CDS_LIB"mstr_standard"
BODY_TYPE"PLUMBING"
HDL_TAP"TRUE";
"B \NAC \NWC"9;
"S \NAC"
BN"21"57;
%"TAP"
"6","(-5575,2625)","0","mstr_standard","I44";
;
CDS_LIB"mstr_standard"
BODY_TYPE"PLUMBING"
HDL_TAP"TRUE";
"B \NAC \NWC"9;
"S \NAC"
BN"22"58;
%"TAP"
"6","(-5575,2675)","0","mstr_standard","I45";
;
CDS_LIB"mstr_standard"
BODY_TYPE"PLUMBING"
HDL_TAP"TRUE";
"B \NAC \NWC"9;
"S \NAC"
BN"23"59;
%"TAP"
"6","(-5575,2725)","0","mstr_standard","I46";
;
CDS_LIB"mstr_standard"
BODY_TYPE"PLUMBING"
HDL_TAP"TRUE";
"B \NAC \NWC"9;
"S \NAC"
BN"24"60;
%"TAP"
"6","(-5575,2825)","0","mstr_standard","I47";
;
CDS_LIB"mstr_standard"
BODY_TYPE"PLUMBING"
HDL_TAP"TRUE";
"B \NAC \NWC"9;
"S \NAC"
BN"26"62;
%"TAP"
"6","(-5575,2775)","0","mstr_standard","I48";
;
CDS_LIB"mstr_standard"
BODY_TYPE"PLUMBING"
HDL_TAP"TRUE";
"B \NAC \NWC"9;
"S \NAC"
BN"25"61;
%"TAP"
"6","(-5575,2875)","0","mstr_standard","I49";
;
CDS_LIB"mstr_standard"
BODY_TYPE"PLUMBING"
HDL_TAP"TRUE";
"B \NAC \NWC"9;
"S \NAC"
BN"27"63;
%"TAP"
"6","(-5575,625)","0","mstr_standard","I5";
;
CDS_LIB"mstr_standard"
BODY_TYPE"PLUMBING"
HDL_TAP"TRUE";
"B \NAC \NWC"10;
"S \NAC"
BN"0"43;
%"TAP"
"6","(-5575,2925)","0","mstr_standard","I50";
;
CDS_LIB"mstr_standard"
BODY_TYPE"PLUMBING"
HDL_TAP"TRUE";
"B \NAC \NWC"9;
"S \NAC"
BN"28"64;
%"TAP"
"6","(-5575,2975)","0","mstr_standard","I51";
;
CDS_LIB"mstr_standard"
BODY_TYPE"PLUMBING"
HDL_TAP"TRUE";
"B \NAC \NWC"9;
"S \NAC"
BN"29"65;
%"TAP"
"6","(-5575,3075)","0","mstr_standard","I52";
;
CDS_LIB"mstr_standard"
BODY_TYPE"PLUMBING"
HDL_TAP"TRUE";
"B \NAC \NWC"9;
"S \NAC"
BN"31"67;
%"TAP"
"6","(-5575,3025)","0","mstr_standard","I53";
;
CDS_LIB"mstr_standard"
BODY_TYPE"PLUMBING"
HDL_TAP"TRUE";
"B \NAC \NWC"9;
"S \NAC"
BN"30"66;
%"TAP"
"6","(-5575,3125)","0","mstr_standard","I54";
;
CDS_LIB"mstr_standard"
BODY_TYPE"PLUMBING"
HDL_TAP"TRUE";
"B \NAC \NWC"9;
"S \NAC"
BN"32"68;
%"TAP"
"6","(-5575,3175)","0","mstr_standard","I55";
;
CDS_LIB"mstr_standard"
BODY_TYPE"PLUMBING"
HDL_TAP"TRUE";
"B \NAC \NWC"9;
"S \NAC"
BN"33"69;
%"TAP"
"6","(-5575,3225)","0","mstr_standard","I56";
;
CDS_LIB"mstr_standard"
BODY_TYPE"PLUMBING"
HDL_TAP"TRUE";
"B \NAC \NWC"9;
"S \NAC"
BN"34"18;
%"TAP"
"6","(-5575,3325)","0","mstr_standard","I57";
;
CDS_LIB"mstr_standard"
BODY_TYPE"PLUMBING"
HDL_TAP"TRUE";
"B \NAC \NWC"9;
"S \NAC"
BN"36"71;
%"TAP"
"6","(-5575,3275)","0","mstr_standard","I58";
;
CDS_LIB"mstr_standard"
BODY_TYPE"PLUMBING"
HDL_TAP"TRUE";
"B \NAC \NWC"9;
"S \NAC"
BN"35"70;
%"TAP"
"6","(-5575,3375)","0","mstr_standard","I59";
;
CDS_LIB"mstr_standard"
BODY_TYPE"PLUMBING"
HDL_TAP"TRUE";
"B \NAC \NWC"9;
"S \NAC"
BN"37"72;
%"TAP"
"6","(-5575,675)","0","mstr_standard","I6";
;
CDS_LIB"mstr_standard"
BODY_TYPE"PLUMBING"
HDL_TAP"TRUE";
"B \NAC \NWC"10;
"S \NAC"
BN"1"44;
%"TAP"
"6","(-5575,3425)","0","mstr_standard","I60";
;
CDS_LIB"mstr_standard"
BODY_TYPE"PLUMBING"
HDL_TAP"TRUE";
"B \NAC \NWC"9;
"S \NAC"
BN"38"73;
%"TAP"
"6","(-5575,3475)","0","mstr_standard","I61";
;
CDS_LIB"mstr_standard"
BODY_TYPE"PLUMBING"
HDL_TAP"TRUE";
"B \NAC \NWC"9;
"S \NAC"
BN"39"74;
%"TAP"
"6","(-5575,3525)","0","mstr_standard","I62";
;
CDS_LIB"mstr_standard"
BODY_TYPE"PLUMBING"
HDL_TAP"TRUE";
"B \NAC \NWC"9;
"S \NAC"
BN"40"75;
%"TAP"
"6","(-5575,3575)","0","mstr_standard","I63";
;
CDS_LIB"mstr_standard"
BODY_TYPE"PLUMBING"
HDL_TAP"TRUE";
"B \NAC \NWC"9;
"S \NAC"
BN"41"15;
%"TAP"
"6","(-5575,3625)","0","mstr_standard","I64";
;
CDS_LIB"mstr_standard"
BODY_TYPE"PLUMBING"
HDL_TAP"TRUE";
"B \NAC \NWC"9;
"S \NAC"
BN"42"76;
%"TAP"
"6","(-5575,3675)","0","mstr_standard","I65";
;
CDS_LIB"mstr_standard"
BODY_TYPE"PLUMBING"
HDL_TAP"TRUE";
"B \NAC \NWC"9;
"S \NAC"
BN"43"77;
%"TAP"
"6","(-5575,3725)","0","mstr_standard","I66";
;
CDS_LIB"mstr_standard"
BODY_TYPE"PLUMBING"
HDL_TAP"TRUE";
"B \NAC \NWC"9;
"S \NAC"
BN"44"78;
%"TAP"
"6","(-5575,3775)","0","mstr_standard","I67";
;
CDS_LIB"mstr_standard"
BODY_TYPE"PLUMBING"
HDL_TAP"TRUE";
"B \NAC \NWC"9;
"S \NAC"
BN"45"79;
%"TAP"
"6","(-5575,3825)","0","mstr_standard","I68";
;
CDS_LIB"mstr_standard"
BODY_TYPE"PLUMBING"
HDL_TAP"TRUE";
"B \NAC \NWC"9;
"S \NAC"
BN"46"80;
%"TAP"
"6","(-5575,3875)","0","mstr_standard","I69";
;
CDS_LIB"mstr_standard"
BODY_TYPE"PLUMBING"
HDL_TAP"TRUE";
"B \NAC \NWC"9;
"S \NAC"
BN"47"81;
%"TAP"
"6","(-5575,775)","0","mstr_standard","I7";
;
CDS_LIB"mstr_standard"
BODY_TYPE"PLUMBING"
HDL_TAP"TRUE";
"B \NAC \NWC"10;
"S \NAC"
BN"3"46;
%"TAP"
"6","(-5575,3925)","0","mstr_standard","I70";
;
CDS_LIB"mstr_standard"
BODY_TYPE"PLUMBING"
HDL_TAP"TRUE";
"B \NAC \NWC"9;
"S \NAC"
BN"48"82;
%"TAP"
"6","(-5575,3975)","0","mstr_standard","I71";
;
CDS_LIB"mstr_standard"
BODY_TYPE"PLUMBING"
HDL_TAP"TRUE";
"B \NAC \NWC"9;
"S \NAC"
BN"49"83;
%"TAP"
"6","(-5575,4025)","0","mstr_standard","I73";
;
CDS_LIB"mstr_standard"
BODY_TYPE"PLUMBING"
HDL_TAP"TRUE";
"B \NAC \NWC"9;
"S \NAC"
BN"50"84;
%"TAP"
"6","(-5575,4075)","0","mstr_standard","I74";
;
CDS_LIB"mstr_standard"
BODY_TYPE"PLUMBING"
HDL_TAP"TRUE";
"B \NAC \NWC"9;
"S \NAC"
BN"51"85;
%"TAP"
"6","(-5575,4125)","0","mstr_standard","I75";
;
CDS_LIB"mstr_standard"
BODY_TYPE"PLUMBING"
HDL_TAP"TRUE";
"B \NAC \NWC"9;
"S \NAC"
BN"52"16;
%"TAP"
"6","(-5575,4175)","0","mstr_standard","I76";
;
CDS_LIB"mstr_standard"
BODY_TYPE"PLUMBING"
HDL_TAP"TRUE";
"B \NAC \NWC"9;
"S \NAC"
BN"53"86;
%"TAP"
"6","(-5575,4225)","0","mstr_standard","I77";
;
CDS_LIB"mstr_standard"
BODY_TYPE"PLUMBING"
HDL_TAP"TRUE";
"B \NAC \NWC"9;
"S \NAC"
BN"54"87;
%"TAP"
"6","(-5575,4275)","0","mstr_standard","I78";
;
CDS_LIB"mstr_standard"
BODY_TYPE"PLUMBING"
HDL_TAP"TRUE";
"B \NAC \NWC"9;
"S \NAC"
BN"55"13;
%"TAP"
"6","(-5575,4325)","0","mstr_standard","I79";
;
CDS_LIB"mstr_standard"
BODY_TYPE"PLUMBING"
HDL_TAP"TRUE";
"B \NAC \NWC"9;
"S \NAC"
BN"56"88;
%"TAP"
"6","(-5575,725)","0","mstr_standard","I8";
;
CDS_LIB"mstr_standard"
BODY_TYPE"PLUMBING"
HDL_TAP"TRUE";
"B \NAC \NWC"10;
"S \NAC"
BN"2"45;
%"TAP"
"6","(-5575,4375)","0","mstr_standard","I80";
;
CDS_LIB"mstr_standard"
BODY_TYPE"PLUMBING"
HDL_TAP"TRUE";
"B \NAC \NWC"9;
"S \NAC"
BN"57"89;
%"TAP"
"6","(-5575,4425)","0","mstr_standard","I81";
;
CDS_LIB"mstr_standard"
BODY_TYPE"PLUMBING"
HDL_TAP"TRUE";
"B \NAC \NWC"9;
"S \NAC"
BN"58"90;
%"TAP"
"6","(-5575,4475)","0","mstr_standard","I82";
;
CDS_LIB"mstr_standard"
BODY_TYPE"PLUMBING"
HDL_TAP"TRUE";
"B \NAC \NWC"9;
"S \NAC"
BN"59"91;
%"TAP"
"6","(-5575,4525)","0","mstr_standard","I83";
;
CDS_LIB"mstr_standard"
BODY_TYPE"PLUMBING"
HDL_TAP"TRUE";
"B \NAC \NWC"9;
"S \NAC"
BN"60"92;
%"TAP"
"6","(-5575,4575)","0","mstr_standard","I84";
;
CDS_LIB"mstr_standard"
BODY_TYPE"PLUMBING"
HDL_TAP"TRUE";
"B \NAC \NWC"9;
"S \NAC"
BN"61"93;
%"TAP"
"6","(-5575,4625)","0","mstr_standard","I85";
;
CDS_LIB"mstr_standard"
BODY_TYPE"PLUMBING"
HDL_TAP"TRUE";
"B \NAC \NWC"9;
"S \NAC"
BN"62"94;
%"TAP"
"6","(-5575,4675)","0","mstr_standard","I86";
;
CDS_LIB"mstr_standard"
BODY_TYPE"PLUMBING"
HDL_TAP"TRUE";
"B \NAC \NWC"9;
"S \NAC"
BN"63"95;
%"TAP"
"6","(-2850,775)","2","mstr_standard","I87";
;
CDS_LIB"mstr_standard"
BODY_TYPE"PLUMBING"
HDL_TAP"TRUE";
"B \NAC \NWC"4;
"S \NAC"
BN"1"117;
%"TAP"
"6","(-2850,725)","2","mstr_standard","I88";
;
CDS_LIB"mstr_standard"
BODY_TYPE"PLUMBING"
HDL_TAP"TRUE";
"B \NAC \NWC"4;
"S \NAC"
BN"0"116;
%"TAP"
"6","(-2850,825)","2","mstr_standard","I89";
;
CDS_LIB"mstr_standard"
BODY_TYPE"PLUMBING"
HDL_TAP"TRUE";
"B \NAC \NWC"5;
"S \NAC"
BN"0"114;
%"TAP"
"6","(-5575,875)","0","mstr_standard","I9";
;
CDS_LIB"mstr_standard"
BODY_TYPE"PLUMBING"
HDL_TAP"TRUE";
"B \NAC \NWC"11;
"S \NAC"
BN"1"40;
%"TAP"
"6","(-2850,875)","2","mstr_standard","I90";
;
CDS_LIB"mstr_standard"
BODY_TYPE"PLUMBING"
HDL_TAP"TRUE";
"B \NAC \NWC"5;
"S \NAC"
BN"1"115;
%"TAP"
"6","(-2850,1075)","2","mstr_standard","I91";
;
CDS_LIB"mstr_standard"
BODY_TYPE"PLUMBING"
HDL_TAP"TRUE";
"B \NAC \NWC"7;
"S \NAC"
BN"2"104;
%"TAP"
"6","(-2850,1025)","2","mstr_standard","I92";
;
CDS_LIB"mstr_standard"
BODY_TYPE"PLUMBING"
HDL_TAP"TRUE";
"B \NAC \NWC"7;
"S \NAC"
BN"1"103;
%"TAP"
"6","(-2850,975)","2","mstr_standard","I93";
;
CDS_LIB"mstr_standard"
BODY_TYPE"PLUMBING"
HDL_TAP"TRUE";
"B \NAC \NWC"7;
"S \NAC"
BN"0"102;
%"TAP"
"6","(-2850,1175)","2","mstr_standard","I94";
;
CDS_LIB"mstr_standard"
BODY_TYPE"PLUMBING"
HDL_TAP"TRUE";
"B \NAC \NWC"7;
"S \NAC"
BN"4"106;
%"TAP"
"6","(-2850,1125)","2","mstr_standard","I95";
;
CDS_LIB"mstr_standard"
BODY_TYPE"PLUMBING"
HDL_TAP"TRUE";
"B \NAC \NWC"7;
"S \NAC"
BN"3"105;
%"TAP"
"6","(-2850,1225)","2","mstr_standard","I96";
;
CDS_LIB"mstr_standard"
BODY_TYPE"PLUMBING"
HDL_TAP"TRUE";
"B \NAC \NWC"7;
"S \NAC"
BN"5"107;
%"TAP"
"6","(-2850,1275)","2","mstr_standard","I97";
;
CDS_LIB"mstr_standard"
BODY_TYPE"PLUMBING"
HDL_TAP"TRUE";
"B \NAC \NWC"7;
"S \NAC"
BN"6"108;
%"TAP"
"6","(-2850,1325)","2","mstr_standard","I98";
;
CDS_LIB"mstr_standard"
BODY_TYPE"PLUMBING"
HDL_TAP"TRUE";
"B \NAC \NWC"7;
"S \NAC"
BN"7"109;
%"TAP"
"6","(-2850,1425)","2","mstr_standard","I99";
;
CDS_LIB"mstr_standard"
BODY_TYPE"PLUMBING"
HDL_TAP"TRUE";
"B \NAC \NWC"8;
"S \NAC"
BN"0"96;
END.
